# T6G (Grand Teton) — schematic netlist excerpt (pin names and nets, part order shuffled) for the footprints in the layout excerpt that follows; sources: Cadence DE-HDL packaged netlist, KiCad conversion of 04192023_DAF0TMB3IC0_F0TG_MB_C_brd_V02_OCP.brd

R4200  Q_RES  1K 1% EMPTY  pkg 0402LF  page 235 : A = P3V3_AUX ; B = U273_3_ADD0
R8313  Q_RES  1K 1% CHIP  pkg 0402LF  page 193 : A = PVDD18_S5_P0 ; B = PVDDCR_CPU0_P0_OCP_N_R

(kicad_pcb
	(version 20260206)
	(generator "pcbnew")
	(generator_version "10.0")
	(general
		(thickness 1.6)
		(legacy_teardrops no)
	)
	(paper "A4")
	(title_block
		(title "04192023_DAF0TMB3IC0_F0TG_MB_C_brd_V02_OCP.brd")
		(comment 1 "Grand Teton / footprints 2124-2125 of 8354")
	)
	(layers
		(0 "F.Cu" signal "TOP")
		(4 "In1.Cu" signal "GND")
		(6 "In2.Cu" signal "IN1")
		(8 "In3.Cu" signal "GND1")
		(10 "In4.Cu" signal "IN2")
		(12 "In5.Cu" signal "GND2")
		(14 "In6.Cu" signal "IN3")
		(16 "In7.Cu" signal "GND3")
		(18 "In8.Cu" signal "VCC")
		(20 "In9.Cu" signal "VCC1")
		(22 "In10.Cu" signal "GND4")
		(24 "In11.Cu" signal "IN4")
		(26 "In12.Cu" signal "GND5")
		(28 "In13.Cu" signal "IN5")
		(30 "In14.Cu" signal "GND6")
		(32 "In15.Cu" signal "IN6")
		(34 "In16.Cu" signal "GND7")
		(2 "B.Cu" signal "BOTTOM")
		(9 "F.Adhes" user "F.Adhesive")
		(11 "B.Adhes" user "B.Adhesive")
		(13 "F.Paste" user "Package Geometry/Pastemask Top")
		(15 "B.Paste" user "Package Geometry/Pastemask Bottom")
		(5 "F.SilkS" user "Ref Des/Silkscreen Top")
		(7 "B.SilkS" user "Ref Des/Silkscreen Bottom")
		(1 "F.Mask" user "Board Geometry/Soldermask Top")
		(3 "B.Mask" user "Board Geometry/Soldermask Bottom")
		(17 "Dwgs.User" user "User.Drawings")
		(19 "Cmts.User" user "User.Comments")
		(21 "Eco1.User" user "User.Eco1")
		(23 "Eco2.User" user "User.Eco2")
		(25 "Edge.Cuts" user "Board Geometry/Outline")
		(27 "Margin" user)
		(31 "F.CrtYd" user "Package Geometry/Place Bound Top")
		(29 "B.CrtYd" user "Package Geometry/Place Bound Bottom")
		(35 "F.Fab" user "Ref Des/Assembly Top")
		(33 "B.Fab" user "Ref Des/Assembly Bottom")
	)
	(footprint ""
		(layer "F.Cu")
		(at 123.767342 -16.50111 180)
		(property "Reference" "R4200"
			(at 0 0 180)
			(layer "F.SilkS")
			(hide yes)
			(effects
				(font
					(size 1.27 1.27)
				)
			)
		)
		(property "Value" ""
			(at 0 0 180)
			(layer "F.Fab")
			(effects
				(font
					(size 1.27 1.27)
				)
			)
		)
		(duplicate_pad_numbers_are_jumpers no)
		(fp_line
			(start 0.7874 0.4064)
			(end -0.7874 0.4064)
			(stroke
				(width 0.1524)
				(type default)
			)
			(layer "F.SilkS")
		)
		(fp_line
			(start 0.7874 -0.4064)
			(end 0.7874 0.4064)
			(stroke
				(width 0.1524)
				(type default)
			)
			(layer "F.SilkS")
		)
		(fp_line
			(start -0.7874 0.4064)
			(end -0.7874 -0.4064)
			(stroke
				(width 0.1524)
				(type default)
			)
			(layer "F.SilkS")
		)
		(fp_line
			(start -0.7874 -0.4064)
			(end 0.7874 -0.4064)
			(stroke
				(width 0.1524)
				(type default)
			)
			(layer "F.SilkS")
		)
		(fp_line
			(start 0.67945 0.3048)
			(end 0.120396 0.3048)
			(stroke
				(width 0.1)
				(type default)
			)
			(layer "F.Fab")
		)
		(fp_line
			(start 0.67945 -0.3048)
			(end 0.67945 0.3048)
			(stroke
				(width 0.1)
				(type default)
			)
			(layer "F.Fab")
		)
		(fp_line
			(start 0.12065 -0.2794)
			(end 0.12065 -0.3048)
			(stroke
				(width 0.1)
				(type default)
			)
			(layer "F.Fab")
		)
		(fp_line
			(start 0.12065 -0.3048)
			(end 0.67945 -0.3048)
			(stroke
				(width 0.1)
				(type default)
			)
			(layer "F.Fab")
		)
		(fp_line
			(start 0.120396 0.3048)
			(end 0.120396 0.2794)
			(stroke
				(width 0.1)
				(type default)
			)
			(layer "F.Fab")
		)
		(fp_line
			(start 0.120396 0.2794)
			(end -0.12065 0.2794)
			(stroke
				(width 0.1)
				(type default)
			)
			(layer "F.Fab")
		)
		(fp_line
			(start -0.12065 0.3048)
			(end -0.67945 0.3048)
			(stroke
				(width 0.1)
				(type default)
			)
			(layer "F.Fab")
		)
		(fp_line
			(start -0.12065 0.2794)
			(end -0.12065 0.3048)
			(stroke
				(width 0.1)
				(type default)
			)
			(layer "F.Fab")
		)
		(fp_line
			(start -0.12065 -0.2794)
			(end 0.12065 -0.2794)
			(stroke
				(width 0.1)
				(type default)
			)
			(layer "F.Fab")
		)
		(fp_line
			(start -0.12065 -0.305054)
			(end -0.12065 -0.2794)
			(stroke
				(width 0.1)
				(type default)
			)
			(layer "F.Fab")
		)
		(fp_line
			(start -0.67945 0.3048)
			(end -0.67945 -0.305054)
			(stroke
				(width 0.1)
				(type default)
			)
			(layer "F.Fab")
		)
		(fp_line
			(start -0.67945 -0.305054)
			(end -0.12065 -0.305054)
			(stroke
				(width 0.1)
				(type default)
			)
			(layer "F.Fab")
		)
		(pad "1" smd circle
			(at -0.40005 0 180)
			(size 0 0)
			(layers "F.Cu" "F.Mask" "F.Paste")
			(net "P3V3_AUX")
		)
		(pad "2" smd circle
			(at 0.40005 0 180)
			(size 0 0)
			(layers "F.Cu" "F.Mask" "F.Paste")
			(net "U273_3_ADD0")
		)
	)
	(footprint ""
		(layer "F.Cu")
		(at 384.113278 -143.250158 180)
		(property "Reference" "R8313"
			(at 0 0 180)
			(layer "F.SilkS")
			(hide yes)
			(effects
				(font
					(size 1.27 1.27)
				)
			)
		)
		(property "Value" ""
			(at 0 0 180)
			(layer "F.Fab")
			(effects
				(font
					(size 1.27 1.27)
				)
			)
		)
		(duplicate_pad_numbers_are_jumpers no)
		(fp_line
			(start 0.7874 0.4064)
			(end -0.7874 0.4064)
			(stroke
				(width 0.1524)
				(type default)
			)
			(layer "F.SilkS")
		)
		(fp_line
			(start 0.7874 -0.4064)
			(end 0.7874 0.4064)
			(stroke
				(width 0.1524)
				(type default)
			)
			(layer "F.SilkS")
		)
		(fp_line
			(start -0.7874 0.4064)
			(end -0.7874 -0.4064)
			(stroke
				(width 0.1524)
				(type default)
			)
			(layer "F.SilkS")
		)
		(fp_line
			(start -0.7874 -0.4064)
			(end 0.7874 -0.4064)
			(stroke
				(width 0.1524)
				(type default)
			)
			(layer "F.SilkS")
		)
		(fp_line
			(start 0.67945 0.3048)
			(end 0.120396 0.3048)
			(stroke
				(width 0.1)
				(type default)
			)
			(layer "F.Fab")
		)
		(fp_line
			(start 0.67945 -0.3048)
			(end 0.67945 0.3048)
			(stroke
				(width 0.1)
				(type default)
			)
			(layer "F.Fab")
		)
		(fp_line
			(start 0.12065 -0.2794)
			(end 0.12065 -0.3048)
			(stroke
				(width 0.1)
				(type default)
			)
			(layer "F.Fab")
		)
		(fp_line
			(start 0.12065 -0.3048)
			(end 0.67945 -0.3048)
			(stroke
				(width 0.1)
				(type default)
			)
			(layer "F.Fab")
		)
		(fp_line
			(start 0.120396 0.3048)
			(end 0.120396 0.2794)
			(stroke
				(width 0.1)
				(type default)
			)
			(layer "F.Fab")
		)
		(fp_line
			(start 0.120396 0.2794)
			(end -0.12065 0.2794)
			(stroke
				(width 0.1)
				(type default)
			)
			(layer "F.Fab")
		)
		(fp_line
			(start -0.12065 0.3048)
			(end -0.67945 0.3048)
			(stroke
				(width 0.1)
				(type default)
			)
			(layer "F.Fab")
		)
		(fp_line
			(start -0.12065 0.2794)
			(end -0.12065 0.3048)
			(stroke
				(width 0.1)
				(type default)
			)
			(layer "F.Fab")
		)
		(fp_line
			(start -0.12065 -0.2794)
			(end 0.12065 -0.2794)
			(stroke
				(width 0.1)
				(type default)
			)
			(layer "F.Fab")
		)
		(fp_line
			(start -0.12065 -0.305054)
			(end -0.12065 -0.2794)
			(stroke
				(width 0.1)
				(type default)
			)
			(layer "F.Fab")
		)
		(fp_line
			(start -0.67945 0.3048)
			(end -0.67945 -0.305054)
			(stroke
				(width 0.1)
				(type default)
			)
			(layer "F.Fab")
		)
		(fp_line
			(start -0.67945 -0.305054)
			(end -0.12065 -0.305054)
			(stroke
				(width 0.1)
				(type default)
			)
			(layer "F.Fab")
		)
		(pad "1" smd circle
			(at -0.40005 0 180)
			(size 0 0)
			(layers "F.Cu" "F.Mask" "F.Paste")
			(net "PVDD18_S5_P0")
		)
		(pad "2" smd circle
			(at 0.40005 0 180)
			(size 0 0)
			(layers "F.Cu" "F.Mask" "F.Paste")
			(net "PVDDCR_CPU0_P0_OCP_N_R")
		)
	)
)
